(kicad_pcb
	(version 20260206)
	(generator "pcbnew")
	(generator_version "10.0")
	(general
		(thickness 1.6)
		(legacy_teardrops no)
	)
	(paper "A4")
	(title_block
		(title "15969-1a.1015WZS0858.brd")
		(comment 1 "Tioga Pass / footprints 8-13 of 295")
	)
	(layers
		(0 "F.Cu" signal "TOP")
		(4 "In1.Cu" signal "L2GND")
		(6 "In2.Cu" signal "L3")
		(8 "In3.Cu" signal "L4")
		(10 "In4.Cu" signal "L5GND")
		(2 "B.Cu" signal "BOTTOM")
		(9 "F.Adhes" user "F.Adhesive")
		(11 "B.Adhes" user "B.Adhesive")
		(13 "F.Paste" user "Package Geometry/Pastemask Top")
		(15 "B.Paste" user "Package Geometry/Pastemask Bottom")
		(5 "F.SilkS" user "Ref Des/Silkscreen Top")
		(7 "B.SilkS" user "Ref Des/Silkscreen Bottom")
		(1 "F.Mask" user "Board Geometry/Soldermask Top")
		(3 "B.Mask" user "Board Geometry/Soldermask Bottom")
		(17 "Dwgs.User" user "User.Drawings")
		(19 "Cmts.User" user "User.Comments")
		(21 "Eco1.User" user "User.Eco1")
		(23 "Eco2.User" user "User.Eco2")
		(25 "Edge.Cuts" user "Board Geometry/Outline")
		(27 "Margin" user)
		(31 "F.CrtYd" user "Package Geometry/Place Bound Top")
		(29 "B.CrtYd" user "Package Geometry/Place Bound Bottom")
		(35 "F.Fab" user "Ref Des/Assembly Top")
		(33 "B.Fab" user "Ref Des/Assembly Bottom")
	)
	(footprint ""
		(layer "F.Cu")
		(at 31.25724 -24.06142 180)
		(property "Reference" "R33"
			(at 0 0 180)
			(layer "F.SilkS")
			(hide yes)
			(effects
				(font
					(size 1.27 1.27)
				)
			)
		)
		(property "Value" "0R2F-1-GP"
			(at 0.064008 -3.993896 180)
			(unlocked yes)
			(layer "F.Fab")
			(hide yes)
			(effects
				(font
					(size 1.016 1.016)
					(thickness 0.1524)
				)
			)
		)
		(property "Device Type" "R402H16"
			(at 0.064008 -5.517896 180)
			(unlocked yes)
			(layer "F.Fab")
			(hide yes)
			(effects
				(font
					(size 1.016 1.016)
					(thickness 0.1524)
				)
			)
		)
		(duplicate_pad_numbers_are_jumpers no)
		(fp_line
			(start 0.508 -0.9398)
			(end -0.508 -0.9398)
			(stroke
				(width 0.1524)
				(type default)
			)
			(layer "F.SilkS")
		)
		(fp_line
			(start -0.508 -0.9398)
			(end -0.508 0.9398)
			(stroke
				(width 0.1524)
				(type default)
			)
			(layer "F.SilkS")
		)
		(fp_rect
			(start -0.508 0.9398)
			(end 0.508 -0.9398)
			(stroke
				(width 0)
				(type default)
			)
			(fill no)
			(layer "F.CrtYd")
		)
		(fp_rect
			(start -0.508 0.9398)
			(end 0.508 -0.9398)
			(stroke
				(width 0)
				(type default)
			)
			(fill no)
			(layer "F.Fab")
		)
		(pad "1" smd custom
			(at 0 -0.4445 180)
			(size 0.1397 0.1397)
			(layers "F.Cu" "F.Mask" "F.Paste")
			(net "SMDAT_BMC_SLOT3")
			(options
				(clearance outline)
				(anchor circle)
			)
			(primitives
				(gr_poly
					(pts
						(arc
							(start -0.1778 -0.2794)
							(mid -0.249642 -0.249642)
							(end -0.2794 -0.1778)
						)
						(arc
							(start -0.2794 0.1778)
							(mid -0.249642 0.249642)
							(end -0.1778 0.2794)
						)
						(arc
							(start 0.1778 0.2794)
							(mid 0.249642 0.249642)
							(end 0.2794 0.1778)
						)
						(arc
							(start 0.2794 -0.1778)
							(mid 0.249642 -0.249642)
							(end 0.1778 -0.2794)
						)
					)
					(width 0)
					(fill yes)
				)
			)
		)
		(pad "2" smd custom
			(at 0 0.4445 180)
			(size 0.1397 0.1397)
			(layers "F.Cu" "F.Mask" "F.Paste")
			(net "SMDAT_BMC_SLOT3_R")
			(options
				(clearance outline)
				(anchor circle)
			)
			(primitives
				(gr_poly
					(pts
						(arc
							(start -0.1778 -0.2794)
							(mid -0.249642 -0.249642)
							(end -0.2794 -0.1778)
						)
						(arc
							(start -0.2794 0.1778)
							(mid -0.249642 0.249642)
							(end -0.1778 0.2794)
						)
						(arc
							(start 0.1778 0.2794)
							(mid 0.249642 0.249642)
							(end 0.2794 0.1778)
						)
						(arc
							(start 0.2794 -0.1778)
							(mid 0.249642 -0.249642)
							(end 0.1778 -0.2794)
						)
					)
					(width 0)
					(fill yes)
				)
			)
		)
	)
	(footprint ""
		(layer "F.Cu")
		(at 91.7956 -17.8308 90)
		(property "Reference" "U10"
			(at 0 0 90)
			(layer "F.SilkS")
			(hide yes)
			(effects
				(font
					(size 1.27 1.27)
				)
			)
		)
		(property "Value" "SN74LVC1G08DCKR-GP"
			(at -2.3368 -8.6868 90)
			(unlocked yes)
			(layer "F.Fab")
			(hide yes)
			(effects
				(font
					(size 1.016 1.016)
					(thickness 0.1524)
				)
			)
		)
		(property "Device Type" "SC70-5H44"
			(at -2.3114 -10.414 90)
			(unlocked yes)
			(layer "F.Fab")
			(hide yes)
			(effects
				(font
					(size 1.016 1.016)
					(thickness 0.1524)
				)
			)
		)
		(duplicate_pad_numbers_are_jumpers no)
		(fp_line
			(start 1.3843 -1.8034)
			(end 1.3843 -1.1176)
			(stroke
				(width 0.3302)
				(type default)
			)
			(layer "F.SilkS")
		)
		(fp_line
			(start 0.6604 -1.8034)
			(end 1.3843 -1.8034)
			(stroke
				(width 0.3302)
				(type default)
			)
			(layer "F.SilkS")
		)
		(fp_line
			(start 1.27 -1.7018)
			(end 1.27 1.7018)
			(stroke
				(width 0.1524)
				(type default)
			)
			(layer "F.SilkS")
		)
		(fp_line
			(start -1.27 -1.7018)
			(end 1.27 -1.7018)
			(stroke
				(width 0.1524)
				(type default)
			)
			(layer "F.SilkS")
		)
		(fp_line
			(start 1.27 1.7018)
			(end -1.27 1.7018)
			(stroke
				(width 0.1524)
				(type default)
			)
			(layer "F.SilkS")
		)
		(fp_line
			(start -1.27 1.7018)
			(end -1.27 -1.7018)
			(stroke
				(width 0.1524)
				(type default)
			)
			(layer "F.SilkS")
		)
		(fp_rect
			(start -1.524 1.9558)
			(end 1.524 -1.9558)
			(stroke
				(width 0)
				(type default)
			)
			(fill no)
			(layer "F.CrtYd")
		)
		(fp_poly
			(pts
				(xy -1.524 -1.9558) (xy 1.524 -1.9558) (xy 1.524 1.9558) (xy -1.524 1.9558)
			)
			(stroke
				(width 0)
				(type default)
			)
			(fill no)
			(layer "F.Fab")
		)
		(pad "1" smd rect
			(at 0.65024 -0.8255 90)
			(size 0.4064 1.2192)
			(layers "F.Cu" "F.Mask" "F.Paste")
			(net "PERST_N")
		)
		(pad "2" smd rect
			(at 0 -0.8255 90)
			(size 0.4064 1.2192)
			(layers "F.Cu" "F.Mask" "F.Paste")
			(net "PERST_N_1_R")
		)
		(pad "3" smd rect
			(at -0.65024 -0.8255 90)
			(size 0.4064 1.2192)
			(layers "F.Cu" "F.Mask" "F.Paste")
			(net "GND")
		)
		(pad "4" smd rect
			(at -0.65024 0.8255 90)
			(size 0.4064 1.2192)
			(layers "F.Cu" "F.Mask" "F.Paste")
			(net "PERST_SLOT_N")
		)
		(pad "5" smd rect
			(at 0.65024 0.8255 90)
			(size 0.4064 1.2192)
			(layers "F.Cu" "F.Mask" "F.Paste")
			(net "P3V3_STBY")
		)
	)
	(footprint ""
		(layer "F.Cu")
		(at 87.6554 -17.272 -90)
		(property "Reference" "R71"
			(at 0 0 270)
			(layer "F.SilkS")
			(hide yes)
			(effects
				(font
					(size 1.27 1.27)
				)
			)
		)
		(property "Value" "0R2F-1-GP"
			(at 0.064008 -3.993896 270)
			(unlocked yes)
			(layer "F.Fab")
			(hide yes)
			(effects
				(font
					(size 1.016 1.016)
					(thickness 0.1524)
				)
			)
		)
		(property "Device Type" "R402H16"
			(at 0.064008 -5.517896 270)
			(unlocked yes)
			(layer "F.Fab")
			(hide yes)
			(effects
				(font
					(size 1.016 1.016)
					(thickness 0.1524)
				)
			)
		)
		(duplicate_pad_numbers_are_jumpers no)
		(fp_line
			(start -0.508 -0.9398)
			(end -0.508 0.9398)
			(stroke
				(width 0.1524)
				(type default)
			)
			(layer "F.SilkS")
		)
		(fp_line
			(start 0.508 -0.9398)
			(end -0.508 -0.9398)
			(stroke
				(width 0.1524)
				(type default)
			)
			(layer "F.SilkS")
		)
		(fp_rect
			(start -0.508 0.9398)
			(end 0.508 -0.9398)
			(stroke
				(width 0)
				(type default)
			)
			(fill no)
			(layer "F.CrtYd")
		)
		(fp_rect
			(start -0.508 0.9398)
			(end 0.508 -0.9398)
			(stroke
				(width 0)
				(type default)
			)
			(fill no)
			(layer "F.Fab")
		)
		(pad "1" smd custom
			(at 0 -0.4445 270)
			(size 0.1397 0.1397)
			(layers "F.Cu" "F.Mask" "F.Paste")
			(net "RESET_O_1")
			(options
				(clearance outline)
				(anchor circle)
			)
			(primitives
				(gr_poly
					(pts
						(arc
							(start -0.1778 -0.2794)
							(mid -0.249642 -0.249642)
							(end -0.2794 -0.1778)
						)
						(arc
							(start -0.2794 0.1778)
							(mid -0.249642 0.249642)
							(end -0.1778 0.2794)
						)
						(arc
							(start 0.1778 0.2794)
							(mid 0.249642 0.249642)
							(end 0.2794 0.1778)
						)
						(arc
							(start 0.2794 -0.1778)
							(mid 0.249642 -0.249642)
							(end 0.1778 -0.2794)
						)
					)
					(width 0)
					(fill yes)
				)
			)
		)
		(pad "2" smd custom
			(at 0 0.4445 270)
			(size 0.1397 0.1397)
			(layers "F.Cu" "F.Mask" "F.Paste")
			(net "PERST_O_1_R")
			(options
				(clearance outline)
				(anchor circle)
			)
			(primitives
				(gr_poly
					(pts
						(arc
							(start -0.1778 -0.2794)
							(mid -0.249642 -0.249642)
							(end -0.2794 -0.1778)
						)
						(arc
							(start -0.2794 0.1778)
							(mid -0.249642 0.249642)
							(end -0.1778 0.2794)
						)
						(arc
							(start 0.1778 0.2794)
							(mid 0.249642 0.249642)
							(end 0.2794 0.1778)
						)
						(arc
							(start 0.2794 -0.1778)
							(mid 0.249642 -0.249642)
							(end 0.1778 -0.2794)
						)
					)
					(width 0)
					(fill yes)
				)
			)
		)
	)
	(footprint ""
		(layer "F.Cu")
		(at 116.5606 -19.05)
		(property "Reference" "R131"
			(at 0 0 0)
			(layer "F.SilkS")
			(hide yes)
			(effects
				(font
					(size 1.27 1.27)
				)
			)
		)
		(property "Value" "10KR2F-2-GP"
			(at 0.064008 -3.993896 0)
			(unlocked yes)
			(layer "F.Fab")
			(hide yes)
			(effects
				(font
					(size 1.016 1.016)
					(thickness 0.1524)
				)
			)
		)
		(property "Device Type" "R402H16"
			(at 0.064008 -5.517896 0)
			(unlocked yes)
			(layer "F.Fab")
			(hide yes)
			(effects
				(font
					(size 1.016 1.016)
					(thickness 0.1524)
				)
			)
		)
		(duplicate_pad_numbers_are_jumpers no)
		(fp_line
			(start -0.508 -0.9398)
			(end -0.508 0.9398)
			(stroke
				(width 0.1524)
				(type default)
			)
			(layer "F.SilkS")
		)
		(fp_line
			(start 0.508 -0.9398)
			(end -0.508 -0.9398)
			(stroke
				(width 0.1524)
				(type default)
			)
			(layer "F.SilkS")
		)
		(fp_rect
			(start -0.508 0.9398)
			(end 0.508 -0.9398)
			(stroke
				(width 0)
				(type default)
			)
			(fill no)
			(layer "F.CrtYd")
		)
		(fp_rect
			(start -0.508 0.9398)
			(end 0.508 -0.9398)
			(stroke
				(width 0)
				(type default)
			)
			(fill no)
			(layer "F.Fab")
		)
		(pad "1" smd custom
			(at 0 -0.4445)
			(size 0.1397 0.1397)
			(layers "F.Cu" "F.Mask" "F.Paste")
			(net "P3V3_STBY")
			(options
				(clearance outline)
				(anchor circle)
			)
			(primitives
				(gr_poly
					(pts
						(arc
							(start -0.1778 -0.2794)
							(mid -0.249642 -0.249642)
							(end -0.2794 -0.1778)
						)
						(arc
							(start -0.2794 0.1778)
							(mid -0.249642 0.249642)
							(end -0.1778 0.2794)
						)
						(arc
							(start 0.1778 0.2794)
							(mid 0.249642 0.249642)
							(end 0.2794 0.1778)
						)
						(arc
							(start 0.2794 -0.1778)
							(mid 0.249642 -0.249642)
							(end 0.1778 -0.2794)
						)
					)
					(width 0)
					(fill yes)
				)
			)
		)
		(pad "2" smd custom
			(at 0 0.4445)
			(size 0.1397 0.1397)
			(layers "F.Cu" "F.Mask" "F.Paste")
			(net "GPIO_B_EXP_A2")
			(options
				(clearance outline)
				(anchor circle)
			)
			(primitives
				(gr_poly
					(pts
						(arc
							(start -0.1778 -0.2794)
							(mid -0.249642 -0.249642)
							(end -0.2794 -0.1778)
						)
						(arc
							(start -0.2794 0.1778)
							(mid -0.249642 0.249642)
							(end -0.1778 0.2794)
						)
						(arc
							(start 0.1778 0.2794)
							(mid 0.249642 0.249642)
							(end 0.2794 0.1778)
						)
						(arc
							(start 0.2794 -0.1778)
							(mid 0.249642 -0.249642)
							(end 0.1778 -0.2794)
						)
					)
					(width 0)
					(fill yes)
				)
			)
		)
	)
	(footprint ""
		(layer "F.Cu")
		(at 94.5134 -16.8656)
		(property "Reference" "R70"
			(at 0 0 0)
			(layer "F.SilkS")
			(hide yes)
			(effects
				(font
					(size 1.27 1.27)
				)
			)
		)
		(property "Value" "0R2F-1-GP"
			(at 0.064008 -3.993896 0)
			(unlocked yes)
			(layer "F.Fab")
			(hide yes)
			(effects
				(font
					(size 1.016 1.016)
					(thickness 0.1524)
				)
			)
		)
		(property "Device Type" "R402H16"
			(at 0.064008 -5.517896 0)
			(unlocked yes)
			(layer "F.Fab")
			(hide yes)
			(effects
				(font
					(size 1.016 1.016)
					(thickness 0.1524)
				)
			)
		)
		(duplicate_pad_numbers_are_jumpers no)
		(fp_line
			(start -0.508 -0.9398)
			(end -0.508 0.9398)
			(stroke
				(width 0.1524)
				(type default)
			)
			(layer "F.SilkS")
		)
		(fp_line
			(start 0.508 -0.9398)
			(end -0.508 -0.9398)
			(stroke
				(width 0.1524)
				(type default)
			)
			(layer "F.SilkS")
		)
		(fp_rect
			(start -0.508 0.9398)
			(end 0.508 -0.9398)
			(stroke
				(width 0)
				(type default)
			)
			(fill no)
			(layer "F.CrtYd")
		)
		(fp_rect
			(start -0.508 0.9398)
			(end 0.508 -0.9398)
			(stroke
				(width 0)
				(type default)
			)
			(fill no)
			(layer "F.Fab")
		)
		(pad "1" smd custom
			(at 0 -0.4445)
			(size 0.1397 0.1397)
			(layers "F.Cu" "F.Mask" "F.Paste")
			(net "PERST_SLOT_N")
			(options
				(clearance outline)
				(anchor circle)
			)
			(primitives
				(gr_poly
					(pts
						(arc
							(start -0.1778 -0.2794)
							(mid -0.249642 -0.249642)
							(end -0.2794 -0.1778)
						)
						(arc
							(start -0.2794 0.1778)
							(mid -0.249642 0.249642)
							(end -0.1778 0.2794)
						)
						(arc
							(start 0.1778 0.2794)
							(mid 0.249642 0.249642)
							(end 0.2794 0.1778)
						)
						(arc
							(start 0.2794 -0.1778)
							(mid 0.249642 -0.249642)
							(end 0.1778 -0.2794)
						)
					)
					(width 0)
					(fill yes)
				)
			)
		)
		(pad "2" smd custom
			(at 0 0.4445)
			(size 0.1397 0.1397)
			(layers "F.Cu" "F.Mask" "F.Paste")
			(net "RESET_BUF_N_SLOT3")
			(options
				(clearance outline)
				(anchor circle)
			)
			(primitives
				(gr_poly
					(pts
						(arc
							(start -0.1778 -0.2794)
							(mid -0.249642 -0.249642)
							(end -0.2794 -0.1778)
						)
						(arc
							(start -0.2794 0.1778)
							(mid -0.249642 0.249642)
							(end -0.1778 0.2794)
						)
						(arc
							(start 0.1778 0.2794)
							(mid 0.249642 0.249642)
							(end 0.2794 0.1778)
						)
						(arc
							(start 0.2794 -0.1778)
							(mid 0.249642 -0.249642)
							(end 0.1778 -0.2794)
						)
					)
					(width 0)
					(fill yes)
				)
			)
		)
	)
	(footprint ""
		(layer "F.Cu")
		(at 21.5646 -19.2786 180)
		(property "Reference" "U14"
			(at 0 0 180)
			(layer "F.SilkS")
			(hide yes)
			(effects
				(font
					(size 1.27 1.27)
				)
			)
		)
		(property "Value" "INA230AIRGTR-GP"
			(at -5.6388 -6.1468 180)
			(unlocked yes)
			(layer "F.Fab")
			(hide yes)
			(effects
				(font
					(size 1.016 1.016)
					(thickness 0.1524)
				)
			)
		)
		(property "Device Type" "QFN16-G1D8-UH40"
			(at -5.6388 -7.6708 180)
			(unlocked yes)
			(layer "F.Fab")
			(hide yes)
			(effects
				(font
					(size 1.016 1.016)
					(thickness 0.1524)
				)
			)
		)
		(duplicate_pad_numbers_are_jumpers no)
		(fp_line
			(start 2.5146 2.5146)
			(end 2.5146 1.2446)
			(stroke
				(width 0.1524)
				(type default)
			)
			(layer "F.SilkS")
		)
		(fp_line
			(start 2.287524 -0.260604)
			(end 2.795524 -0.260604)
			(stroke
				(width 0.1524)
				(type default)
			)
			(layer "F.SilkS")
		)
		(fp_line
			(start 1.2446 2.5146)
			(end 2.5146 2.5146)
			(stroke
				(width 0.1524)
				(type default)
			)
			(layer "F.SilkS")
		)
		(fp_line
			(start -0.248666 2.287524)
			(end -0.248666 3.049524)
			(stroke
				(width 0.1524)
				(type default)
			)
			(layer "F.SilkS")
		)
		(fp_line
			(start -1.2446 -2.5146)
			(end -2.5146 -2.5146)
			(stroke
				(width 0.1524)
				(type default)
			)
			(layer "F.SilkS")
		)
		(fp_line
			(start -2.287524 -0.753364)
			(end -2.795524 -0.753364)
			(stroke
				(width 0.1524)
				(type default)
			)
			(layer "F.SilkS")
		)
		(fp_line
			(start -2.5146 2.5146)
			(end -1.2446 2.5146)
			(stroke
				(width 0.1524)
				(type default)
			)
			(layer "F.SilkS")
		)
		(fp_line
			(start -2.5146 1.2446)
			(end -2.5146 2.5146)
			(stroke
				(width 0.1524)
				(type default)
			)
			(layer "F.SilkS")
		)
		(fp_line
			(start -2.5146 -2.5146)
			(end -2.5146 -1.2446)
			(stroke
				(width 0.1524)
				(type default)
			)
			(layer "F.SilkS")
		)
		(fp_poly
			(pts
				(xy 1.2446 -2.5146) (xy 2.5146 -2.5146) (xy 2.5146 -1.2446)
			)
			(stroke
				(width 0)
				(type default)
			)
			(fill yes)
			(layer "F.SilkS")
		)
		(fp_rect
			(start -1.4986 1.4986)
			(end 1.4986 -1.4986)
			(stroke
				(width 0)
				(type default)
			)
			(fill no)
			(layer "F.CrtYd")
		)
		(fp_poly
			(pts
				(xy -1.4986 -1.4986) (xy -2.5146 -1.4986) (xy -2.5146 -2.5146) (xy 2.5146 -2.5146) (xy 2.5146 2.5146)
				(xy -2.5146 2.5146) (xy -2.5146 -1.4859) (xy -1.4986 -1.4859) (xy -1.4986 1.4986) (xy 1.4986 1.4986)
				(xy 1.4986 -1.4986)
			)
			(stroke
				(width 0)
				(type default)
			)
			(fill no)
			(layer "F.CrtYd")
		)
		(fp_rect
			(start -2.5146 2.5146)
			(end 2.5146 -2.5146)
			(stroke
				(width 0)
				(type default)
			)
			(fill no)
			(layer "F.Fab")
		)
		(pad "1" smd rect
			(at 0.750062 -1.550924 180)
			(size 0.3048 0.9144)
			(layers "F.Cu" "F.Mask" "F.Paste")
			(net "SLOT2_VMONITOR_A1")
		)
		(pad "2" smd rect
			(at 0.249936 -1.550924 180)
			(size 0.3048 0.9144)
			(layers "F.Cu" "F.Mask" "F.Paste")
			(net "SLOT2_VMONITOR_A0")
		)
		(pad "3" smd rect
			(at -0.249936 -1.550924 180)
			(size 0.3048 0.9144)
			(layers "F.Cu" "F.Mask" "F.Paste")
			(net "SMB_VMONITOR_SLOT2_ALERT_N")
		)
		(pad "4" smd rect
			(at -0.750062 -1.550924 180)
			(size 0.3048 0.9144)
			(layers "F.Cu" "F.Mask" "F.Paste")
			(net "SMB_VMONITOR_SLOT2_MUX_SDA")
		)
		(pad "5" smd rect
			(at -1.550924 -0.750062 180)
			(size 0.9144 0.3048)
			(layers "F.Cu" "F.Mask" "F.Paste")
			(net "SMB_VMONITOR_SLOT2_MUX_SCL")
		)
		(pad "6" smd rect
			(at -1.550924 -0.249936 180)
			(size 0.9144 0.3048)
			(layers "F.Cu" "F.Mask" "F.Paste")
			(net "Net_226")
		)
		(pad "7" smd rect
			(at -1.550924 0.249936 180)
			(size 0.9144 0.3048)
			(layers "F.Cu" "F.Mask" "F.Paste")
			(net "Net_227")
		)
		(pad "8" smd rect
			(at -1.550924 0.750062 180)
			(size 0.9144 0.3048)
			(layers "F.Cu" "F.Mask" "F.Paste")
			(net "Net_228")
		)
		(pad "9" smd rect
			(at -0.750062 1.550924 180)
			(size 0.3048 0.9144)
			(layers "F.Cu" "F.Mask" "F.Paste")
			(net "P3V3_STBY")
		)
		(pad "10" smd rect
			(at -0.249936 1.550924 180)
			(size 0.3048 0.9144)
			(layers "F.Cu" "F.Mask" "F.Paste")
			(net "GND")
		)
		(pad "11" smd rect
			(at 0.249936 1.550924 180)
			(size 0.3048 0.9144)
			(layers "F.Cu" "F.Mask" "F.Paste")
			(net "P12V")
		)
		(pad "12" smd rect
			(at 0.750062 1.550924 180)
			(size 0.3048 0.9144)
			(layers "F.Cu" "F.Mask" "F.Paste")
			(net "SLOT2_P12V_SENSE_VN_R")
		)
		(pad "13" smd rect
			(at 1.550924 0.750062 180)
			(size 0.9144 0.3048)
			(layers "F.Cu" "F.Mask" "F.Paste")
			(net "SLOT2_P12V_SENSE_VP_R")
		)
		(pad "14" smd rect
			(at 1.550924 0.249936 180)
			(size 0.9144 0.3048)
			(layers "F.Cu" "F.Mask" "F.Paste")
			(net "Net_223")
		)
		(pad "15" smd rect
			(at 1.550924 -0.249936 180)
			(size 0.9144 0.3048)
			(layers "F.Cu" "F.Mask" "F.Paste")
			(net "Net_224")
		)
		(pad "16" smd rect
			(at 1.550924 -0.750062 180)
			(size 0.9144 0.3048)
			(layers "F.Cu" "F.Mask" "F.Paste")
			(net "Net_225")
		)
		(pad "17" smd rect
			(at 0 0 180)
			(size 1.778 1.778)
			(layers "F.Cu" "F.Mask" "F.Paste")
			(net "GND")
		)
	)
)
